# T6G (Grand Teton) — schematic netlist excerpt (pin names and nets, part order shuffled) for the footprints in the layout excerpt that follows; sources: Cadence DE-HDL packaged netlist, KiCad conversion of 04192023_DAF0TMB3IC0_F0TG_MB_C_brd_V02_OCP.brd

R1307  Q_RES  4.7K 1% EMPTY  pkg 0402LF  page 357 : A = GND ; B = INA230_7_A1

U269  ADC128D818CIMTXNOPB  ADC128D818CIMTX/NOPB IC  pkg TSSOP16XC  page 257
  VREF  = ADC128_VREF
  SDA  = SMB_SEN_TIC_3V3AUX_SDA
  SCL  = SMB_SEN_TIC_3V3AUX_SCL
  GND  = GND
  \v+\  = P3V3_ADC128_VCC
  \int#\  = TP_ADC128_INT
  A0  = ADC128_A0
  A1  = ADC128_A1
  IN7  = P12V_E1S_0_ISENSE_TIC
  IN6  = P3V3_PDB_AUX_ADC_TIC
  IN5  = P3V3_AUX_ADC_TIC
  IN4  = P3V3_ADC_TIC
  IN3  = P5V_ADC_TIC
  IN2  = P12V_OCP_V3_2_ISENSE_TIC
  IN1  = P12V_OCP_SFF_ISENSE_TIC
  IN0  = P12V_AUX_ADC_TIC

(kicad_pcb
	(version 20260206)
	(generator "pcbnew")
	(generator_version "10.0")
	(general
		(thickness 1.6)
		(legacy_teardrops no)
	)
	(paper "A4")
	(title_block
		(title "04192023_DAF0TMB3IC0_F0TG_MB_C_brd_V02_OCP.brd")
		(comment 1 "Grand Teton / footprints 3654-3655 of 8354")
	)
	(layers
		(0 "F.Cu" signal "TOP")
		(4 "In1.Cu" signal "GND")
		(6 "In2.Cu" signal "IN1")
		(8 "In3.Cu" signal "GND1")
		(10 "In4.Cu" signal "IN2")
		(12 "In5.Cu" signal "GND2")
		(14 "In6.Cu" signal "IN3")
		(16 "In7.Cu" signal "GND3")
		(18 "In8.Cu" signal "VCC")
		(20 "In9.Cu" signal "VCC1")
		(22 "In10.Cu" signal "GND4")
		(24 "In11.Cu" signal "IN4")
		(26 "In12.Cu" signal "GND5")
		(28 "In13.Cu" signal "IN5")
		(30 "In14.Cu" signal "GND6")
		(32 "In15.Cu" signal "IN6")
		(34 "In16.Cu" signal "GND7")
		(2 "B.Cu" signal "BOTTOM")
		(9 "F.Adhes" user "F.Adhesive")
		(11 "B.Adhes" user "B.Adhesive")
		(13 "F.Paste" user "Package Geometry/Pastemask Top")
		(15 "B.Paste" user "Package Geometry/Pastemask Bottom")
		(5 "F.SilkS" user "Ref Des/Silkscreen Top")
		(7 "B.SilkS" user "Ref Des/Silkscreen Bottom")
		(1 "F.Mask" user "Board Geometry/Soldermask Top")
		(3 "B.Mask" user "Board Geometry/Soldermask Bottom")
		(17 "Dwgs.User" user "User.Drawings")
		(19 "Cmts.User" user "User.Comments")
		(21 "Eco1.User" user "User.Eco1")
		(23 "Eco2.User" user "User.Eco2")
		(25 "Edge.Cuts" user "Board Geometry/Outline")
		(27 "Margin" user)
		(31 "F.CrtYd" user "Package Geometry/Place Bound Top")
		(29 "B.CrtYd" user "Package Geometry/Place Bound Bottom")
		(35 "F.Fab" user "Ref Des/Assembly Top")
		(33 "B.Fab" user "Ref Des/Assembly Bottom")
	)
	(footprint ""
		(layer "F.Cu")
		(at 19.241516 -40.942514)
		(property "Reference" "R1307"
			(at 0 0 0)
			(layer "F.SilkS")
			(hide yes)
			(effects
				(font
					(size 1.27 1.27)
				)
			)
		)
		(property "Value" ""
			(at 0 0 0)
			(layer "F.Fab")
			(effects
				(font
					(size 1.27 1.27)
				)
			)
		)
		(duplicate_pad_numbers_are_jumpers no)
		(fp_line
			(start -0.7874 -0.4064)
			(end 0.7874 -0.4064)
			(stroke
				(width 0.1524)
				(type default)
			)
			(layer "F.SilkS")
		)
		(fp_line
			(start -0.7874 0.4064)
			(end -0.7874 -0.4064)
			(stroke
				(width 0.1524)
				(type default)
			)
			(layer "F.SilkS")
		)
		(fp_line
			(start 0.7874 -0.4064)
			(end 0.7874 0.4064)
			(stroke
				(width 0.1524)
				(type default)
			)
			(layer "F.SilkS")
		)
		(fp_line
			(start 0.7874 0.4064)
			(end -0.7874 0.4064)
			(stroke
				(width 0.1524)
				(type default)
			)
			(layer "F.SilkS")
		)
		(fp_line
			(start -0.67945 -0.305054)
			(end -0.12065 -0.305054)
			(stroke
				(width 0.1)
				(type default)
			)
			(layer "F.Fab")
		)
		(fp_line
			(start -0.67945 0.3048)
			(end -0.67945 -0.305054)
			(stroke
				(width 0.1)
				(type default)
			)
			(layer "F.Fab")
		)
		(fp_line
			(start -0.12065 -0.305054)
			(end -0.12065 -0.2794)
			(stroke
				(width 0.1)
				(type default)
			)
			(layer "F.Fab")
		)
		(fp_line
			(start -0.12065 -0.2794)
			(end 0.12065 -0.2794)
			(stroke
				(width 0.1)
				(type default)
			)
			(layer "F.Fab")
		)
		(fp_line
			(start -0.12065 0.2794)
			(end -0.12065 0.3048)
			(stroke
				(width 0.1)
				(type default)
			)
			(layer "F.Fab")
		)
		(fp_line
			(start -0.12065 0.3048)
			(end -0.67945 0.3048)
			(stroke
				(width 0.1)
				(type default)
			)
			(layer "F.Fab")
		)
		(fp_line
			(start 0.120396 0.2794)
			(end -0.12065 0.2794)
			(stroke
				(width 0.1)
				(type default)
			)
			(layer "F.Fab")
		)
		(fp_line
			(start 0.120396 0.3048)
			(end 0.120396 0.2794)
			(stroke
				(width 0.1)
				(type default)
			)
			(layer "F.Fab")
		)
		(fp_line
			(start 0.12065 -0.3048)
			(end 0.67945 -0.3048)
			(stroke
				(width 0.1)
				(type default)
			)
			(layer "F.Fab")
		)
		(fp_line
			(start 0.12065 -0.2794)
			(end 0.12065 -0.3048)
			(stroke
				(width 0.1)
				(type default)
			)
			(layer "F.Fab")
		)
		(fp_line
			(start 0.67945 -0.3048)
			(end 0.67945 0.3048)
			(stroke
				(width 0.1)
				(type default)
			)
			(layer "F.Fab")
		)
		(fp_line
			(start 0.67945 0.3048)
			(end 0.120396 0.3048)
			(stroke
				(width 0.1)
				(type default)
			)
			(layer "F.Fab")
		)
		(pad "1" smd circle
			(at -0.40005 0)
			(size 0 0)
			(layers "F.Cu" "F.Mask" "F.Paste")
			(net "GND")
		)
		(pad "2" smd circle
			(at 0.40005 0)
			(size 0 0)
			(layers "F.Cu" "F.Mask" "F.Paste")
			(net "INA230_7_A1")
		)
	)
	(footprint ""
		(layer "F.Cu")
		(at 312.725308 -43.46321)
		(property "Reference" "U269"
			(at -3.27914 -4.806188 0)
			(unlocked yes)
			(layer "F.SilkS")
			(effects
				(font
					(size 0.7874 0.5842)
					(thickness 0.1524)
				)
				(justify left)
			)
		)
		(property "Value" ""
			(at 0 0 0)
			(layer "F.Fab")
			(effects
				(font
					(size 1.27 1.27)
				)
			)
		)
		(duplicate_pad_numbers_are_jumpers no)
		(fp_line
			(start -1.868932 -2.549906)
			(end -1.868932 2.549906)
			(stroke
				(width 0.1524)
				(type default)
			)
			(layer "F.SilkS")
		)
		(fp_line
			(start -1.868932 2.549906)
			(end 1.868932 2.549906)
			(stroke
				(width 0.1524)
				(type default)
			)
			(layer "F.SilkS")
		)
		(fp_line
			(start -1.025906 -2.549906)
			(end -1.868932 -2.549906)
			(stroke
				(width 0.1524)
				(type default)
			)
			(layer "F.SilkS")
		)
		(fp_line
			(start 0 -1.524)
			(end -1.025906 -2.549906)
			(stroke
				(width 0.1524)
				(type default)
			)
			(layer "F.SilkS")
		)
		(fp_line
			(start 1.025906 -2.549906)
			(end 0 -1.524)
			(stroke
				(width 0.1524)
				(type default)
			)
			(layer "F.SilkS")
		)
		(fp_line
			(start 1.868932 -2.549906)
			(end 1.025906 -2.549906)
			(stroke
				(width 0.1524)
				(type default)
			)
			(layer "F.SilkS")
		)
		(fp_line
			(start 1.868932 2.549906)
			(end 1.868932 -2.549906)
			(stroke
				(width 0.1524)
				(type default)
			)
			(layer "F.SilkS")
		)
		(fp_poly
			(pts
				(xy -3.243326 -3.828796) (xy -2.227326 -3.828796) (xy -2.735326 -2.812796)
			)
			(stroke
				(width 0)
				(type default)
			)
			(fill yes)
			(layer "F.SilkS")
		)
		(fp_line
			(start -2.249932 -2.549906)
			(end -2.249932 2.549906)
			(stroke
				(width 0.1)
				(type default)
			)
			(layer "F.Fab")
		)
		(fp_line
			(start -2.249932 2.549906)
			(end 2.249932 2.549906)
			(stroke
				(width 0.1)
				(type default)
			)
			(layer "F.Fab")
		)
		(fp_line
			(start 2.249932 -2.549906)
			(end -2.249932 -2.549906)
			(stroke
				(width 0.1)
				(type default)
			)
			(layer "F.Fab")
		)
		(fp_line
			(start 2.249932 2.549906)
			(end 2.249932 -2.549906)
			(stroke
				(width 0.1)
				(type default)
			)
			(layer "F.Fab")
		)
		(fp_poly
			(pts
				(xy -4.7752 -1.787398) (xy -4.7752 -2.803398) (xy -3.7592 -2.295398)
			)
			(stroke
				(width 0)
				(type default)
			)
			(fill yes)
			(layer "F.Fab")
		)
		(pad "1" smd rect
			(at -2.800096 -2.275078 270)
			(size 0.3556 1.6002)
			(layers "F.Cu" "F.Mask" "F.Paste")
			(net "ADC128_VREF")
		)
		(pad "2" smd rect
			(at -2.800096 -1.625092 270)
			(size 0.3556 1.6002)
			(layers "F.Cu" "F.Mask" "F.Paste")
			(net "SMB_SEN_TIC_3V3AUX_SDA")
		)
		(pad "3" smd rect
			(at -2.800096 -0.975106 270)
			(size 0.3556 1.6002)
			(layers "F.Cu" "F.Mask" "F.Paste")
			(net "SMB_SEN_TIC_3V3AUX_SCL")
		)
		(pad "4" smd rect
			(at -2.800096 -0.32512 270)
			(size 0.3556 1.6002)
			(layers "F.Cu" "F.Mask" "F.Paste")
			(net "GND")
		)
		(pad "5" smd rect
			(at -2.800096 0.32512 270)
			(size 0.3556 1.6002)
			(layers "F.Cu" "F.Mask" "F.Paste")
			(net "P3V3_ADC128_VCC")
		)
		(pad "6" smd rect
			(at -2.800096 0.975106 270)
			(size 0.3556 1.6002)
			(layers "F.Cu" "F.Mask" "F.Paste")
			(net "TP_ADC128_INT")
		)
		(pad "7" smd rect
			(at -2.800096 1.625092 270)
			(size 0.3556 1.6002)
			(layers "F.Cu" "F.Mask" "F.Paste")
			(net "ADC128_A0")
		)
		(pad "8" smd rect
			(at -2.800096 2.275078 270)
			(size 0.3556 1.6002)
			(layers "F.Cu" "F.Mask" "F.Paste")
			(net "ADC128_A1")
		)
		(pad "9" smd rect
			(at 2.800096 2.275078 270)
			(size 0.3556 1.6002)
			(layers "F.Cu" "F.Mask" "F.Paste")
			(net "P12V_E1S_0_ISENSE_TIC")
		)
		(pad "10" smd rect
			(at 2.800096 1.625092 270)
			(size 0.3556 1.6002)
			(layers "F.Cu" "F.Mask" "F.Paste")
			(net "P3V3_PDB_AUX_ADC_TIC")
		)
		(pad "11" smd rect
			(at 2.800096 0.975106 270)
			(size 0.3556 1.6002)
			(layers "F.Cu" "F.Mask" "F.Paste")
			(net "P3V3_AUX_ADC_TIC")
		)
		(pad "12" smd rect
			(at 2.800096 0.32512 270)
			(size 0.3556 1.6002)
			(layers "F.Cu" "F.Mask" "F.Paste")
			(net "P3V3_ADC_TIC")
		)
		(pad "13" smd rect
			(at 2.800096 -0.32512 270)
			(size 0.3556 1.6002)
			(layers "F.Cu" "F.Mask" "F.Paste")
			(net "P5V_ADC_TIC")
		)
		(pad "14" smd rect
			(at 2.800096 -0.975106 270)
			(size 0.3556 1.6002)
			(layers "F.Cu" "F.Mask" "F.Paste")
			(net "P12V_OCP_V3_2_ISENSE_TIC")
		)
		(pad "15" smd rect
			(at 2.800096 -1.625092 270)
			(size 0.3556 1.6002)
			(layers "F.Cu" "F.Mask" "F.Paste")
			(net "P12V_OCP_SFF_ISENSE_TIC")
		)
		(pad "16" smd rect
			(at 2.800096 -2.275078 270)
			(size 0.3556 1.6002)
			(layers "F.Cu" "F.Mask" "F.Paste")
			(net "P12V_AUX_ADC_TIC")
		)
	)
)
